(kicad_pcb
	(version 20260206)
	(generator "pcbnew")
	(generator_version "10.0")
	(general
		(thickness 1.6)
		(legacy_teardrops no)
	)
	(paper "A4")
	(title_block
		(title "dpb — 14545-sa.0730WZS0815.brd")
		(comment 1 "Honey Badger (Wiwynn) / footprints 349-356 of 1066")
	)
	(layers
		(0 "F.Cu" signal "TOP")
		(4 "In1.Cu" signal "L2GND")
		(6 "In2.Cu" signal "L3")
		(8 "In3.Cu" signal "L4VCC")
		(10 "In4.Cu" signal "L5VCC")
		(12 "In5.Cu" signal "L6")
		(14 "In6.Cu" signal "L7GND")
		(2 "B.Cu" signal "BOTTOM")
		(9 "F.Adhes" user "F.Adhesive")
		(11 "B.Adhes" user "B.Adhesive")
		(13 "F.Paste" user "Package Geometry/Pastemask Top")
		(15 "B.Paste" user "Package Geometry/Pastemask Bottom")
		(5 "F.SilkS" user "Ref Des/Silkscreen Top")
		(7 "B.SilkS" user "Ref Des/Silkscreen Bottom")
		(1 "F.Mask" user "Board Geometry/Soldermask Top")
		(3 "B.Mask" user "Board Geometry/Soldermask Bottom")
		(17 "Dwgs.User" user "User.Drawings")
		(19 "Cmts.User" user "User.Comments")
		(21 "Eco1.User" user "User.Eco1")
		(23 "Eco2.User" user "User.Eco2")
		(25 "Edge.Cuts" user "Board Geometry/Outline")
		(27 "Margin" user)
		(31 "F.CrtYd" user "Package Geometry/Place Bound Top")
		(29 "B.CrtYd" user "Package Geometry/Place Bound Bottom")
		(35 "F.Fab" user "Ref Des/Assembly Top")
		(33 "B.Fab" user "Ref Des/Assembly Bottom")
	)
	(footprint ""
		(layer "F.Cu")
		(at 53.721 -208.534 180)
		(property "Reference" "R575"
			(at 0 0 180)
			(layer "F.SilkS")
			(hide yes)
			(effects
				(font
					(size 1.27 1.27)
				)
			)
		)
		(property "Value" "300KR2F-GP"
			(at 0.064008 -3.993896 180)
			(unlocked yes)
			(layer "F.Fab")
			(hide yes)
			(effects
				(font
					(size 1.016 1.016)
					(thickness 0.1524)
				)
			)
		)
		(property "Device Type" "R402H16"
			(at 0.064008 -5.517896 180)
			(unlocked yes)
			(layer "F.Fab")
			(hide yes)
			(effects
				(font
					(size 1.016 1.016)
					(thickness 0.1524)
				)
			)
		)
		(duplicate_pad_numbers_are_jumpers no)
		(fp_line
			(start 0.508 -0.9398)
			(end -0.508 -0.9398)
			(stroke
				(width 0.1524)
				(type default)
			)
			(layer "F.SilkS")
		)
		(fp_line
			(start -0.508 -0.9398)
			(end -0.508 0.9398)
			(stroke
				(width 0.1524)
				(type default)
			)
			(layer "F.SilkS")
		)
		(fp_rect
			(start -0.508 0.9398)
			(end 0.508 -0.9398)
			(stroke
				(width 0)
				(type default)
			)
			(fill no)
			(layer "F.CrtYd")
		)
		(fp_rect
			(start -0.508 0.9398)
			(end 0.508 -0.9398)
			(stroke
				(width 0)
				(type default)
			)
			(fill no)
			(layer "F.Fab")
		)
		(pad "1" smd custom
			(at 0 -0.4445 180)
			(size 0.1397 0.1397)
			(layers "F.Cu" "F.Mask" "F.Paste")
			(net "SW_HDD12_N")
			(options
				(clearance outline)
				(anchor circle)
			)
			(primitives
				(gr_poly
					(pts
						(arc
							(start -0.1778 -0.2794)
							(mid -0.249642 -0.249642)
							(end -0.2794 -0.1778)
						)
						(arc
							(start -0.2794 0.1778)
							(mid -0.249642 0.249642)
							(end -0.1778 0.2794)
						)
						(arc
							(start 0.1778 0.2794)
							(mid 0.249642 0.249642)
							(end 0.2794 0.1778)
						)
						(arc
							(start 0.2794 -0.1778)
							(mid 0.249642 -0.249642)
							(end 0.1778 -0.2794)
						)
					)
					(width 0)
					(fill yes)
				)
			)
		)
		(pad "2" smd custom
			(at 0 0.4445 180)
			(size 0.1397 0.1397)
			(layers "F.Cu" "F.Mask" "F.Paste")
			(net "P12V")
			(options
				(clearance outline)
				(anchor circle)
			)
			(primitives
				(gr_poly
					(pts
						(arc
							(start -0.1778 -0.2794)
							(mid -0.249642 -0.249642)
							(end -0.2794 -0.1778)
						)
						(arc
							(start -0.2794 0.1778)
							(mid -0.249642 0.249642)
							(end -0.1778 0.2794)
						)
						(arc
							(start 0.1778 0.2794)
							(mid 0.249642 0.249642)
							(end 0.2794 0.1778)
						)
						(arc
							(start 0.2794 -0.1778)
							(mid 0.249642 -0.249642)
							(end 0.1778 -0.2794)
						)
					)
					(width 0)
					(fill yes)
				)
			)
		)
	)
	(footprint ""
		(layer "F.Cu")
		(at 224.679256 -452.682102 90)
		(property "Reference" "R104"
			(at 0 0 90)
			(layer "F.SilkS")
			(hide yes)
			(effects
				(font
					(size 1.27 1.27)
				)
			)
		)
		(property "Value" "330R2F-GP"
			(at 0.064008 -3.993896 90)
			(unlocked yes)
			(layer "F.Fab")
			(hide yes)
			(effects
				(font
					(size 1.016 1.016)
					(thickness 0.1524)
				)
			)
		)
		(property "Device Type" "R402H16"
			(at 0.064008 -5.517896 90)
			(unlocked yes)
			(layer "F.Fab")
			(hide yes)
			(effects
				(font
					(size 1.016 1.016)
					(thickness 0.1524)
				)
			)
		)
		(duplicate_pad_numbers_are_jumpers no)
		(fp_line
			(start 0.508 -0.9398)
			(end -0.508 -0.9398)
			(stroke
				(width 0.1524)
				(type default)
			)
			(layer "F.SilkS")
		)
		(fp_line
			(start -0.508 -0.9398)
			(end -0.508 0.9398)
			(stroke
				(width 0.1524)
				(type default)
			)
			(layer "F.SilkS")
		)
		(fp_rect
			(start -0.508 0.9398)
			(end 0.508 -0.9398)
			(stroke
				(width 0)
				(type default)
			)
			(fill no)
			(layer "F.CrtYd")
		)
		(fp_rect
			(start -0.508 0.9398)
			(end 0.508 -0.9398)
			(stroke
				(width 0)
				(type default)
			)
			(fill no)
			(layer "F.Fab")
		)
		(pad "1" smd custom
			(at 0 -0.4445 90)
			(size 0.1397 0.1397)
			(layers "F.Cu" "F.Mask" "F.Paste")
			(net "P3V3_HDD0_LED")
			(options
				(clearance outline)
				(anchor circle)
			)
			(primitives
				(gr_poly
					(pts
						(arc
							(start -0.1778 -0.2794)
							(mid -0.249642 -0.249642)
							(end -0.2794 -0.1778)
						)
						(arc
							(start -0.2794 0.1778)
							(mid -0.249642 0.249642)
							(end -0.1778 0.2794)
						)
						(arc
							(start 0.1778 0.2794)
							(mid 0.249642 0.249642)
							(end 0.2794 0.1778)
						)
						(arc
							(start 0.2794 -0.1778)
							(mid 0.249642 -0.249642)
							(end 0.1778 -0.2794)
						)
					)
					(width 0)
					(fill yes)
				)
			)
		)
		(pad "2" smd custom
			(at 0 0.4445 90)
			(size 0.1397 0.1397)
			(layers "F.Cu" "F.Mask" "F.Paste")
			(net "FLT_HDD0")
			(options
				(clearance outline)
				(anchor circle)
			)
			(primitives
				(gr_poly
					(pts
						(arc
							(start -0.1778 -0.2794)
							(mid -0.249642 -0.249642)
							(end -0.2794 -0.1778)
						)
						(arc
							(start -0.2794 0.1778)
							(mid -0.249642 0.249642)
							(end -0.1778 0.2794)
						)
						(arc
							(start 0.1778 0.2794)
							(mid 0.249642 0.249642)
							(end 0.2794 0.1778)
						)
						(arc
							(start 0.2794 -0.1778)
							(mid 0.249642 -0.249642)
							(end 0.1778 -0.2794)
						)
					)
					(width 0)
					(fill yes)
				)
			)
		)
	)
	(footprint ""
		(layer "F.Cu")
		(at 30.352746 -281.4447 180)
		(property "Reference" "R210"
			(at 0 0 180)
			(layer "F.SilkS")
			(hide yes)
			(effects
				(font
					(size 1.27 1.27)
				)
			)
		)
		(property "Value" "0R2J-2-GP"
			(at 0.064008 -3.993896 180)
			(unlocked yes)
			(layer "F.Fab")
			(hide yes)
			(effects
				(font
					(size 1.016 1.016)
					(thickness 0.1524)
				)
			)
		)
		(property "Device Type" "R402H16"
			(at 0.064008 -5.517896 180)
			(unlocked yes)
			(layer "F.Fab")
			(hide yes)
			(effects
				(font
					(size 1.016 1.016)
					(thickness 0.1524)
				)
			)
		)
		(duplicate_pad_numbers_are_jumpers no)
		(fp_line
			(start 0.508 -0.9398)
			(end -0.508 -0.9398)
			(stroke
				(width 0.1524)
				(type default)
			)
			(layer "F.SilkS")
		)
		(fp_line
			(start -0.508 -0.9398)
			(end -0.508 0.9398)
			(stroke
				(width 0.1524)
				(type default)
			)
			(layer "F.SilkS")
		)
		(fp_rect
			(start -0.508 0.9398)
			(end 0.508 -0.9398)
			(stroke
				(width 0)
				(type default)
			)
			(fill no)
			(layer "F.CrtYd")
		)
		(fp_rect
			(start -0.508 0.9398)
			(end 0.508 -0.9398)
			(stroke
				(width 0)
				(type default)
			)
			(fill no)
			(layer "F.Fab")
		)
		(pad "1" smd custom
			(at 0 -0.4445 180)
			(size 0.1397 0.1397)
			(layers "F.Cu" "F.Mask" "F.Paste")
			(net "SW_PWR_HDD7")
			(options
				(clearance outline)
				(anchor circle)
			)
			(primitives
				(gr_poly
					(pts
						(arc
							(start -0.1778 -0.2794)
							(mid -0.249642 -0.249642)
							(end -0.2794 -0.1778)
						)
						(arc
							(start -0.2794 0.1778)
							(mid -0.249642 0.249642)
							(end -0.1778 0.2794)
						)
						(arc
							(start 0.1778 0.2794)
							(mid 0.249642 0.249642)
							(end 0.2794 0.1778)
						)
						(arc
							(start 0.2794 -0.1778)
							(mid 0.249642 -0.249642)
							(end 0.1778 -0.2794)
						)
					)
					(width 0)
					(fill yes)
				)
			)
		)
		(pad "2" smd custom
			(at 0 0.4445 180)
			(size 0.1397 0.1397)
			(layers "F.Cu" "F.Mask" "F.Paste")
			(net "SW_PWR_R_HDD7")
			(options
				(clearance outline)
				(anchor circle)
			)
			(primitives
				(gr_poly
					(pts
						(arc
							(start -0.1778 -0.2794)
							(mid -0.249642 -0.249642)
							(end -0.2794 -0.1778)
						)
						(arc
							(start -0.2794 0.1778)
							(mid -0.249642 0.249642)
							(end -0.1778 0.2794)
						)
						(arc
							(start 0.1778 0.2794)
							(mid 0.249642 0.249642)
							(end 0.2794 0.1778)
						)
						(arc
							(start 0.2794 -0.1778)
							(mid 0.249642 -0.249642)
							(end 0.1778 -0.2794)
						)
					)
					(width 0)
					(fill yes)
				)
			)
		)
	)
	(footprint ""
		(layer "F.Cu")
		(at 77.469746 -396.8877 90)
		(property "Reference" "R196"
			(at 0 0 90)
			(layer "F.SilkS")
			(hide yes)
			(effects
				(font
					(size 1.27 1.27)
				)
			)
		)
		(property "Value" "0R2J-2-GP"
			(at 0.064008 -3.993896 90)
			(unlocked yes)
			(layer "F.Fab")
			(hide yes)
			(effects
				(font
					(size 1.016 1.016)
					(thickness 0.1524)
				)
			)
		)
		(property "Device Type" "R402H16"
			(at 0.064008 -5.517896 90)
			(unlocked yes)
			(layer "F.Fab")
			(hide yes)
			(effects
				(font
					(size 1.016 1.016)
					(thickness 0.1524)
				)
			)
		)
		(duplicate_pad_numbers_are_jumpers no)
		(fp_line
			(start 0.508 -0.9398)
			(end -0.508 -0.9398)
			(stroke
				(width 0.1524)
				(type default)
			)
			(layer "F.SilkS")
		)
		(fp_line
			(start -0.508 -0.9398)
			(end -0.508 0.9398)
			(stroke
				(width 0.1524)
				(type default)
			)
			(layer "F.SilkS")
		)
		(fp_rect
			(start -0.508 0.9398)
			(end 0.508 -0.9398)
			(stroke
				(width 0)
				(type default)
			)
			(fill no)
			(layer "F.CrtYd")
		)
		(fp_rect
			(start -0.508 0.9398)
			(end 0.508 -0.9398)
			(stroke
				(width 0)
				(type default)
			)
			(fill no)
			(layer "F.Fab")
		)
		(pad "1" smd custom
			(at 0 -0.4445 90)
			(size 0.1397 0.1397)
			(layers "F.Cu" "F.Mask" "F.Paste")
			(net "SW_PWR_HDD6")
			(options
				(clearance outline)
				(anchor circle)
			)
			(primitives
				(gr_poly
					(pts
						(arc
							(start -0.1778 -0.2794)
							(mid -0.249642 -0.249642)
							(end -0.2794 -0.1778)
						)
						(arc
							(start -0.2794 0.1778)
							(mid -0.249642 0.249642)
							(end -0.1778 0.2794)
						)
						(arc
							(start 0.1778 0.2794)
							(mid 0.249642 0.249642)
							(end 0.2794 0.1778)
						)
						(arc
							(start 0.2794 -0.1778)
							(mid 0.249642 -0.249642)
							(end 0.1778 -0.2794)
						)
					)
					(width 0)
					(fill yes)
				)
			)
		)
		(pad "2" smd custom
			(at 0 0.4445 90)
			(size 0.1397 0.1397)
			(layers "F.Cu" "F.Mask" "F.Paste")
			(net "SW_PWR_R_HDD6")
			(options
				(clearance outline)
				(anchor circle)
			)
			(primitives
				(gr_poly
					(pts
						(arc
							(start -0.1778 -0.2794)
							(mid -0.249642 -0.249642)
							(end -0.2794 -0.1778)
						)
						(arc
							(start -0.2794 0.1778)
							(mid -0.249642 0.249642)
							(end -0.1778 0.2794)
						)
						(arc
							(start 0.1778 0.2794)
							(mid 0.249642 0.249642)
							(end 0.2794 0.1778)
						)
						(arc
							(start 0.2794 -0.1778)
							(mid 0.249642 -0.249642)
							(end 0.1778 -0.2794)
						)
					)
					(width 0)
					(fill yes)
				)
			)
		)
	)
	(footprint ""
		(layer "F.Cu")
		(at 35.940746 -321.8307)
		(property "Reference" "TP36"
			(at 0 0 0)
			(layer "F.SilkS")
			(hide yes)
			(effects
				(font
					(size 1.27 1.27)
				)
			)
		)
		(property "Value" "TPAD32-GP"
			(at 0 -3.166364 0)
			(unlocked yes)
			(layer "F.Fab")
			(hide yes)
			(effects
				(font
					(size 1.016 1.016)
					(thickness 0.1524)
				)
			)
		)
		(property "Device Type" "TPAD32"
			(at 0 -4.690618 0)
			(unlocked yes)
			(layer "F.Fab")
			(hide yes)
			(effects
				(font
					(size 1.016 1.016)
					(thickness 0.1524)
				)
			)
		)
		(duplicate_pad_numbers_are_jumpers no)
		(fp_poly
			(pts
				(arc
					(start 0.4064 0)
					(mid -0.4064 0)
					(end 0.4064 0)
				)
			)
			(stroke
				(width 0)
				(type default)
			)
			(fill no)
			(layer "F.CrtYd")
		)
		(fp_poly
			(pts
				(arc
					(start 0.7112 0)
					(mid -0.7112 0)
					(end 0.7112 0)
				)
			)
			(stroke
				(width 0)
				(type default)
			)
			(fill no)
			(layer "F.Fab")
		)
		(pad "1" smd circle
			(at 0 0)
			(size 0.8128 0.8128)
			(layers "F.Cu" "F.Mask" "F.Paste")
			(net "ACT_HDD11")
		)
	)
	(footprint ""
		(layer "F.Cu")
		(at 229.742746 -21.9837)
		(property "Reference" "PC7"
			(at 0 0 0)
			(layer "F.SilkS")
			(hide yes)
			(effects
				(font
					(size 1.27 1.27)
				)
			)
		)
		(property "Value" "SCD1U25V2KX-GP"
			(at 1.1811 -2.7051 0)
			(unlocked yes)
			(layer "F.Fab")
			(hide yes)
			(effects
				(font
					(size 1.016 1.016)
					(thickness 0.1524)
				)
			)
		)
		(property "Device Type" "C402H22"
			(at 1.1811 -4.2291 0)
			(unlocked yes)
			(layer "F.Fab")
			(hide yes)
			(effects
				(font
					(size 1.016 1.016)
					(thickness 0.1524)
				)
			)
		)
		(duplicate_pad_numbers_are_jumpers no)
		(fp_rect
			(start -0.4318 0.9525)
			(end 0.4318 -0.9525)
			(stroke
				(width 0)
				(type default)
			)
			(fill no)
			(layer "F.CrtYd")
		)
		(fp_rect
			(start -0.4318 0.9525)
			(end 0.4318 -0.9525)
			(stroke
				(width 0)
				(type default)
			)
			(fill no)
			(layer "F.Fab")
		)
		(pad "1" smd custom
			(at 0 -0.4445)
			(size 0.1524 0.1524)
			(layers "F.Cu" "F.Mask" "F.Paste")
			(net "P5VA_VBST_NET")
			(options
				(clearance outline)
				(anchor circle)
			)
			(primitives
				(gr_poly
					(pts
						(arc
							(start 0.3048 -0.2032)
							(mid 0.275042 -0.275042)
							(end 0.2032 -0.3048)
						)
						(arc
							(start -0.2032 -0.3048)
							(mid -0.275042 -0.275042)
							(end -0.3048 -0.2032)
						)
						(arc
							(start -0.3048 0.2032)
							(mid -0.275042 0.275042)
							(end -0.2032 0.3048)
						)
						(arc
							(start 0.2032 0.3048)
							(mid 0.275042 0.275042)
							(end 0.3048 0.2032)
						)
					)
					(width 0)
					(fill yes)
				)
			)
		)
		(pad "2" smd custom
			(at 0 0.4445)
			(size 0.1524 0.1524)
			(layers "F.Cu" "F.Mask" "F.Paste")
			(net "P5VA_LL")
			(options
				(clearance outline)
				(anchor circle)
			)
			(primitives
				(gr_poly
					(pts
						(arc
							(start 0.3048 -0.2032)
							(mid 0.275042 -0.275042)
							(end 0.2032 -0.3048)
						)
						(arc
							(start -0.2032 -0.3048)
							(mid -0.275042 -0.275042)
							(end -0.3048 -0.2032)
						)
						(arc
							(start -0.3048 0.2032)
							(mid -0.275042 0.275042)
							(end -0.2032 0.3048)
						)
						(arc
							(start 0.2032 0.3048)
							(mid 0.275042 0.275042)
							(end 0.3048 0.2032)
						)
					)
					(width 0)
					(fill yes)
				)
			)
		)
	)
	(footprint ""
		(layer "F.Cu")
		(at 190.754 -395.097)
		(property "Reference" "R122"
			(at 0 0 0)
			(layer "F.SilkS")
			(hide yes)
			(effects
				(font
					(size 1.27 1.27)
				)
			)
		)
		(property "Value" "200KR2F-L-GP"
			(at 0.064008 -3.993896 0)
			(unlocked yes)
			(layer "F.Fab")
			(hide yes)
			(effects
				(font
					(size 1.016 1.016)
					(thickness 0.1524)
				)
			)
		)
		(property "Device Type" "R402H16"
			(at 0.064008 -5.517896 0)
			(unlocked yes)
			(layer "F.Fab")
			(hide yes)
			(effects
				(font
					(size 1.016 1.016)
					(thickness 0.1524)
				)
			)
		)
		(duplicate_pad_numbers_are_jumpers no)
		(fp_line
			(start -0.508 -0.9398)
			(end -0.508 0.9398)
			(stroke
				(width 0.1524)
				(type default)
			)
			(layer "F.SilkS")
		)
		(fp_line
			(start 0.508 -0.9398)
			(end -0.508 -0.9398)
			(stroke
				(width 0.1524)
				(type default)
			)
			(layer "F.SilkS")
		)
		(fp_rect
			(start -0.508 0.9398)
			(end 0.508 -0.9398)
			(stroke
				(width 0)
				(type default)
			)
			(fill no)
			(layer "F.CrtYd")
		)
		(fp_rect
			(start -0.508 0.9398)
			(end 0.508 -0.9398)
			(stroke
				(width 0)
				(type default)
			)
			(fill no)
			(layer "F.Fab")
		)
		(pad "1" smd custom
			(at 0 -0.4445)
			(size 0.1397 0.1397)
			(layers "F.Cu" "F.Mask" "F.Paste")
			(net "P12V")
			(options
				(clearance outline)
				(anchor circle)
			)
			(primitives
				(gr_poly
					(pts
						(arc
							(start -0.1778 -0.2794)
							(mid -0.249642 -0.249642)
							(end -0.2794 -0.1778)
						)
						(arc
							(start -0.2794 0.1778)
							(mid -0.249642 0.249642)
							(end -0.1778 0.2794)
						)
						(arc
							(start 0.1778 0.2794)
							(mid 0.249642 0.249642)
							(end 0.2794 0.1778)
						)
						(arc
							(start 0.2794 -0.1778)
							(mid 0.249642 -0.249642)
							(end 0.1778 -0.2794)
						)
					)
					(width 0)
					(fill yes)
				)
			)
		)
		(pad "2" smd custom
			(at 0 0.4445)
			(size 0.1397 0.1397)
			(layers "F.Cu" "F.Mask" "F.Paste")
			(net "SW_HDD1_P")
			(options
				(clearance outline)
				(anchor circle)
			)
			(primitives
				(gr_poly
					(pts
						(arc
							(start -0.1778 -0.2794)
							(mid -0.249642 -0.249642)
							(end -0.2794 -0.1778)
						)
						(arc
							(start -0.2794 0.1778)
							(mid -0.249642 0.249642)
							(end -0.1778 0.2794)
						)
						(arc
							(start 0.1778 0.2794)
							(mid 0.249642 0.249642)
							(end 0.2794 0.1778)
						)
						(arc
							(start 0.2794 -0.1778)
							(mid 0.249642 -0.249642)
							(end 0.1778 -0.2794)
						)
					)
					(width 0)
					(fill yes)
				)
			)
		)
	)
	(footprint ""
		(layer "F.Cu")
		(at 239.902746 -27.9527 180)
		(property "Reference" "PR13"
			(at 0 0 180)
			(layer "F.SilkS")
			(hide yes)
			(effects
				(font
					(size 1.27 1.27)
				)
			)
		)
		(property "Value" "115KR2F-GP"
			(at 0.064008 -3.993896 180)
			(unlocked yes)
			(layer "F.Fab")
			(hide yes)
			(effects
				(font
					(size 1.016 1.016)
					(thickness 0.1524)
				)
			)
		)
		(property "Device Type" "R402H16"
			(at 0.064008 -5.517896 180)
			(unlocked yes)
			(layer "F.Fab")
			(hide yes)
			(effects
				(font
					(size 1.016 1.016)
					(thickness 0.1524)
				)
			)
		)
		(duplicate_pad_numbers_are_jumpers no)
		(fp_line
			(start 0.508 -0.9398)
			(end -0.508 -0.9398)
			(stroke
				(width 0.1524)
				(type default)
			)
			(layer "F.SilkS")
		)
		(fp_line
			(start -0.508 -0.9398)
			(end -0.508 0.9398)
			(stroke
				(width 0.1524)
				(type default)
			)
			(layer "F.SilkS")
		)
		(fp_rect
			(start -0.508 0.9398)
			(end 0.508 -0.9398)
			(stroke
				(width 0)
				(type default)
			)
			(fill no)
			(layer "F.CrtYd")
		)
		(fp_rect
			(start -0.508 0.9398)
			(end 0.508 -0.9398)
			(stroke
				(width 0)
				(type default)
			)
			(fill no)
			(layer "F.Fab")
		)
		(pad "1" smd custom
			(at 0 -0.4445 180)
			(size 0.1397 0.1397)
			(layers "F.Cu" "F.Mask" "F.Paste")
			(net "P5VA_TRIP")
			(options
				(clearance outline)
				(anchor circle)
			)
			(primitives
				(gr_poly
					(pts
						(arc
							(start -0.1778 -0.2794)
							(mid -0.249642 -0.249642)
							(end -0.2794 -0.1778)
						)
						(arc
							(start -0.2794 0.1778)
							(mid -0.249642 0.249642)
							(end -0.1778 0.2794)
						)
						(arc
							(start 0.1778 0.2794)
							(mid 0.249642 0.249642)
							(end 0.2794 0.1778)
						)
						(arc
							(start 0.2794 -0.1778)
							(mid 0.249642 -0.249642)
							(end 0.1778 -0.2794)
						)
					)
					(width 0)
					(fill yes)
				)
			)
		)
		(pad "2" smd custom
			(at 0 0.4445 180)
			(size 0.1397 0.1397)
			(layers "F.Cu" "F.Mask" "F.Paste")
			(net "P5VA_AGND")
			(options
				(clearance outline)
				(anchor circle)
			)
			(primitives
				(gr_poly
					(pts
						(arc
							(start -0.1778 -0.2794)
							(mid -0.249642 -0.249642)
							(end -0.2794 -0.1778)
						)
						(arc
							(start -0.2794 0.1778)
							(mid -0.249642 0.249642)
							(end -0.1778 0.2794)
						)
						(arc
							(start 0.1778 0.2794)
							(mid 0.249642 0.249642)
							(end 0.2794 0.1778)
						)
						(arc
							(start 0.2794 -0.1778)
							(mid 0.249642 -0.249642)
							(end 0.1778 -0.2794)
						)
					)
					(width 0)
					(fill yes)
				)
			)
		)
	)
)
